# SCM (Grand Teton) — schematic netlist excerpt (pin names and nets, part order shuffled) for the footprints in the layout excerpt that follows; sources: Cadence DE-HDL packaged netlist, KiCad conversion of 12092022_DA0F0TMDCD0_F0T_Management_Board_D_brd_V3_OCP.brd

C222  Q_CAP  0.1UF 25V 10% X7R  pkg 0402  page 20 : A = P1V2_AUX ; B = GND
L19  Q_INDUCTOR  BLM18EG121SN1D/2A IND  pkg SMLF  page 41 : \1\ = P3V3_AUX ; \2\ = PVCCA_AUX_PLD

(kicad_pcb
	(version 20260206)
	(generator "pcbnew")
	(generator_version "10.0")
	(general
		(thickness 1.6)
		(legacy_teardrops no)
	)
	(paper "A4")
	(title_block
		(title "12092022_DA0F0TMDCD0_F0T_Management_Board_D_brd_V3_OCP.brd")
		(comment 1 "Grand Teton / footprints 1115-1116 of 1440")
	)
	(layers
		(0 "F.Cu" signal "TOP")
		(4 "In1.Cu" signal "GND")
		(6 "In2.Cu" signal "IN1")
		(8 "In3.Cu" signal "GND1")
		(10 "In4.Cu" signal "IN2")
		(12 "In5.Cu" signal "VCC")
		(14 "In6.Cu" signal "VCC1")
		(16 "In7.Cu" signal "IN3")
		(18 "In8.Cu" signal "GND2")
		(20 "In9.Cu" signal "IN4")
		(22 "In10.Cu" signal "GND3")
		(2 "B.Cu" signal "BOTTOM")
		(9 "F.Adhes" user "F.Adhesive")
		(11 "B.Adhes" user "B.Adhesive")
		(13 "F.Paste" user "Package Geometry/Pastemask Top")
		(15 "B.Paste" user "Package Geometry/Pastemask Bottom")
		(5 "F.SilkS" user "Ref Des/Silkscreen Top")
		(7 "B.SilkS" user "Ref Des/Silkscreen Bottom")
		(1 "F.Mask" user "Board Geometry/Soldermask Top")
		(3 "B.Mask" user "Board Geometry/Soldermask Bottom")
		(17 "Dwgs.User" user "User.Drawings")
		(19 "Cmts.User" user "User.Comments")
		(21 "Eco1.User" user "User.Eco1")
		(23 "Eco2.User" user "User.Eco2")
		(25 "Edge.Cuts" user "Board Geometry/Outline")
		(27 "Margin" user)
		(31 "F.CrtYd" user "Package Geometry/Place Bound Top")
		(29 "B.CrtYd" user "Package Geometry/Place Bound Bottom")
		(35 "F.Fab" user "Ref Des/Assembly Top")
		(33 "B.Fab" user "Ref Des/Assembly Bottom")
	)
	(footprint ""
		(layer "B.Cu")
		(at 80.018636 -47.846488)
		(property "Reference" "C222"
			(at 0 0 0)
			(layer "B.SilkS")
			(hide yes)
			(effects
				(font
					(size 1.27 1.27)
				)
				(justify mirror)
			)
		)
		(property "Value" ""
			(at 0 0 0)
			(layer "B.Fab")
			(effects
				(font
					(size 1.27 1.27)
				)
				(justify mirror)
			)
		)
		(duplicate_pad_numbers_are_jumpers no)
		(fp_line
			(start -0.7874 -0.4064)
			(end -0.7874 0.4064)
			(stroke
				(width 0.1524)
				(type default)
			)
			(layer "B.SilkS")
		)
		(fp_line
			(start -0.7874 0.4064)
			(end 0.7874 0.4064)
			(stroke
				(width 0.1524)
				(type default)
			)
			(layer "B.SilkS")
		)
		(fp_line
			(start 0.7874 -0.4064)
			(end -0.7874 -0.4064)
			(stroke
				(width 0.1524)
				(type default)
			)
			(layer "B.SilkS")
		)
		(fp_line
			(start 0.7874 0.4064)
			(end 0.7874 -0.4064)
			(stroke
				(width 0.1524)
				(type default)
			)
			(layer "B.SilkS")
		)
		(fp_line
			(start -0.67945 -0.3048)
			(end -0.67945 0.3048)
			(stroke
				(width 0.1)
				(type default)
			)
			(layer "B.Fab")
		)
		(fp_line
			(start -0.67945 0.3048)
			(end -0.120396 0.3048)
			(stroke
				(width 0.1)
				(type default)
			)
			(layer "B.Fab")
		)
		(fp_line
			(start -0.12065 -0.3048)
			(end -0.67945 -0.3048)
			(stroke
				(width 0.1)
				(type default)
			)
			(layer "B.Fab")
		)
		(fp_line
			(start -0.12065 -0.2794)
			(end -0.12065 -0.3048)
			(stroke
				(width 0.1)
				(type default)
			)
			(layer "B.Fab")
		)
		(fp_line
			(start -0.120396 0.2794)
			(end 0.12065 0.2794)
			(stroke
				(width 0.1)
				(type default)
			)
			(layer "B.Fab")
		)
		(fp_line
			(start -0.120396 0.3048)
			(end -0.120396 0.2794)
			(stroke
				(width 0.1)
				(type default)
			)
			(layer "B.Fab")
		)
		(fp_line
			(start 0.12065 -0.305054)
			(end 0.12065 -0.2794)
			(stroke
				(width 0.1)
				(type default)
			)
			(layer "B.Fab")
		)
		(fp_line
			(start 0.12065 -0.2794)
			(end -0.12065 -0.2794)
			(stroke
				(width 0.1)
				(type default)
			)
			(layer "B.Fab")
		)
		(fp_line
			(start 0.12065 0.2794)
			(end 0.12065 0.3048)
			(stroke
				(width 0.1)
				(type default)
			)
			(layer "B.Fab")
		)
		(fp_line
			(start 0.12065 0.3048)
			(end 0.67945 0.3048)
			(stroke
				(width 0.1)
				(type default)
			)
			(layer "B.Fab")
		)
		(fp_line
			(start 0.67945 -0.305054)
			(end 0.12065 -0.305054)
			(stroke
				(width 0.1)
				(type default)
			)
			(layer "B.Fab")
		)
		(fp_line
			(start 0.67945 0.3048)
			(end 0.67945 -0.305054)
			(stroke
				(width 0.1)
				(type default)
			)
			(layer "B.Fab")
		)
		(pad "1" smd circle
			(at 0.40005 0 180)
			(size 0 0)
			(layers "B.Cu" "B.Mask" "B.Paste")
			(net "P1V2_AUX")
		)
		(pad "2" smd circle
			(at -0.40005 0 180)
			(size 0 0)
			(layers "B.Cu" "B.Mask" "B.Paste")
			(net "GND")
		)
	)
	(footprint ""
		(layer "B.Cu")
		(at 27.305 -101.981 90)
		(property "Reference" "L19"
			(at 0 0 90)
			(layer "B.SilkS")
			(hide yes)
			(effects
				(font
					(size 1.27 1.27)
				)
				(justify mirror)
			)
		)
		(property "Value" ""
			(at 0 0 90)
			(layer "B.Fab")
			(effects
				(font
					(size 1.27 1.27)
				)
				(justify mirror)
			)
		)
		(duplicate_pad_numbers_are_jumpers no)
		(fp_line
			(start 1.27 -0.5842)
			(end -1.27 -0.5842)
			(stroke
				(width 0.1524)
				(type default)
			)
			(layer "B.SilkS")
		)
		(fp_line
			(start 1.27 -0.5588)
			(end 1.27 -0.5842)
			(stroke
				(width 0.1524)
				(type default)
			)
			(layer "B.SilkS")
		)
		(fp_line
			(start 1.27 0.5842)
			(end 1.27 -0.5842)
			(stroke
				(width 0.1524)
				(type default)
			)
			(layer "B.SilkS")
		)
		(fp_line
			(start 0.127 0.5842)
			(end 0.127 -0.5842)
			(stroke
				(width 0.1524)
				(type default)
			)
			(layer "B.SilkS")
		)
		(fp_line
			(start -0.127 0.5842)
			(end -0.127 -0.5842)
			(stroke
				(width 0.1524)
				(type default)
			)
			(layer "B.SilkS")
		)
		(fp_line
			(start -1.27 0.5842)
			(end -1.27 -0.5842)
			(stroke
				(width 0.1524)
				(type default)
			)
			(layer "B.SilkS")
		)
		(fp_line
			(start -1.27 0.5842)
			(end 1.27 0.5842)
			(stroke
				(width 0.1524)
				(type default)
			)
			(layer "B.SilkS")
		)
		(fp_line
			(start 0.9144 -0.508)
			(end -0.9144 -0.508)
			(stroke
				(width 0.1)
				(type default)
			)
			(layer "B.Fab")
		)
		(fp_line
			(start -0.9144 -0.508)
			(end -0.914654 -0.406654)
			(stroke
				(width 0.1)
				(type default)
			)
			(layer "B.Fab")
		)
		(fp_line
			(start 1.194308 -0.406654)
			(end 0.914654 -0.406654)
			(stroke
				(width 0.1)
				(type default)
			)
			(layer "B.Fab")
		)
		(fp_line
			(start 0.914654 -0.406654)
			(end 0.9144 -0.508)
			(stroke
				(width 0.1)
				(type default)
			)
			(layer "B.Fab")
		)
		(fp_line
			(start -0.914654 -0.406654)
			(end -1.193546 -0.406654)
			(stroke
				(width 0.1)
				(type default)
			)
			(layer "B.Fab")
		)
		(fp_line
			(start -1.193546 -0.406654)
			(end -1.1938 0.4064)
			(stroke
				(width 0.1)
				(type default)
			)
			(layer "B.Fab")
		)
		(fp_line
			(start -0.9144 0.4064)
			(end -0.9144 0.508)
			(stroke
				(width 0.1)
				(type default)
			)
			(layer "B.Fab")
		)
		(fp_line
			(start -1.1938 0.4064)
			(end -0.9144 0.4064)
			(stroke
				(width 0.1)
				(type default)
			)
			(layer "B.Fab")
		)
		(fp_line
			(start 1.194308 0.406654)
			(end 1.194308 -0.406654)
			(stroke
				(width 0.1)
				(type default)
			)
			(layer "B.Fab")
		)
		(fp_line
			(start 0.914654 0.406654)
			(end 1.194308 0.406654)
			(stroke
				(width 0.1)
				(type default)
			)
			(layer "B.Fab")
		)
		(fp_line
			(start 0.9144 0.508)
			(end 0.914654 0.406654)
			(stroke
				(width 0.1)
				(type default)
			)
			(layer "B.Fab")
		)
		(fp_line
			(start -0.9144 0.508)
			(end 0.9144 0.508)
			(stroke
				(width 0.1)
				(type default)
			)
			(layer "B.Fab")
		)
		(pad "1" smd rect
			(at 0.7366 0)
			(size 0.7112 0.8128)
			(layers "B.Cu" "B.Mask" "B.Paste")
			(net "P3V3_AUX")
		)
		(pad "2" smd rect
			(at -0.7366 0)
			(size 0.7112 0.8128)
			(layers "B.Cu" "B.Mask" "B.Paste")
			(net "PVCCA_AUX_PLD")
		)
	)
)
